FILE_TYPE = CONNECTIVITY;
{Allegro Design Entry HDL 17.2-2016 S081 (4005846) 1/11/2022}
"PAGE_NUMBER" = 220;
0"NC";
1"SMB_INA230_3V3AUX_SCL";
2"SMB_INA230_2_3V3AUX_SDA_R";
3"SMB_INA230_2_3V3AUX_SCL_R";
4"SMB_INA230_3V3AUX_SDA";
5"SMB_INA230_1_3V3AUX_SDA_R";
6"SMB_INA230_1_3V3AUX_SCL_R";
7"SMB_INA230_5_3V3AUX_SDA_R";
8"SMB_INA230_3_3V3AUX_SCL_R";
9"SMB_INA230_3_3V3AUX_SDA_R";
10"SMB_INA230_4_3V3AUX_SCL_R";
11"SMB_INA230_4_3V3AUX_SDA_R";
12"SMB_INA230_5_3V3AUX_SCL_R";
%"Q_RES"
"1","(825,3225)","0","pure_quanta","I11";
;
PART_NUMBER"CS03322FB03"
TOLERANCE"1%"
MATERIAL"CHIP"
VALUE"33.2"
$LOCATION"R3589"
CDS_LIB"pure_quanta"
PACK_TYPE"0402LF"
WATTAGE"1/16W"
CDS_LOCATION"R3589"
$SEC"1"
CDS_SEC"1";
"B"
$PN"2"2;
"A"
$PN"1"4;
%"Q_RES"
"1","(825,3275)","0","pure_quanta","I16";
;
PART_NUMBER"CS03322FB03"
PACK_TYPE"0402LF"
WATTAGE"1/16W"
MATERIAL"CHIP"
TOLERANCE"1%"
VALUE"33.2"
$LOCATION"R3588"
CDS_LIB"pure_quanta"
CDS_LOCATION"R3588"
$SEC"1"
CDS_SEC"1";
"B"
$PN"2"3;
"A"
$PN"1"1;
%"Q_RES"
"1","(825,3000)","0","pure_quanta","I17";
;
PART_NUMBER"CS03322FB03"
VALUE"33.2"
MATERIAL"CHIP"
TOLERANCE"1%"
WATTAGE"1/16W"
PACK_TYPE"0402LF"
$LOCATION"R3590"
CDS_LIB"pure_quanta"
CDS_LOCATION"R3590"
$SEC"1"
CDS_SEC"1";
"B"
$PN"2"8;
"A"
$PN"1"1;
%"Q_RES"
"1","(825,2950)","0","pure_quanta","I18";
;
PART_NUMBER"CS03322FB03"
TOLERANCE"1%"
MATERIAL"CHIP"
VALUE"33.2"
$LOCATION"R3591"
CDS_LIB"pure_quanta"
WATTAGE"1/16W"
PACK_TYPE"0402LF"
CDS_LOCATION"R3591"
$SEC"1"
CDS_SEC"1";
"B"
$PN"2"9;
"A"
$PN"1"4;
%"Q_RES"
"1","(825,2375)","0","pure_quanta","I19";
;
PART_NUMBER"CS03322FB03"
MATERIAL"CHIP"
TOLERANCE"1%"
VALUE"33.2"
$LOCATION"R3593"
CDS_LIB"pure_quanta"
WATTAGE"1/16W"
PACK_TYPE"0402LF"
CDS_LOCATION"R3593"
$SEC"1"
CDS_SEC"1";
"B"
$PN"2"7;
"A"
$PN"1"4;
%"Q_RES"
"1","(825,2425)","0","pure_quanta","I20";
;
PART_NUMBER"CS03322FB03"
VALUE"33.2"
PACK_TYPE"0402LF"
MATERIAL"CHIP"
TOLERANCE"1%"
WATTAGE"1/16W"
$LOCATION"R3592"
CDS_LIB"pure_quanta"
CDS_LOCATION"R3592"
$SEC"1"
CDS_SEC"1";
"B"
$PN"2"12;
"A"
$PN"1"1;
%"Q_RES"
"1","(850,2700)","0","pure_quanta","I21";
;
PART_NUMBER"CS03322FB03"
WATTAGE"1/16W"
TOLERANCE"1%"
MATERIAL"CHIP"
PACK_TYPE"0402LF"
VALUE"33.2"
$LOCATION"R3594"
CDS_LIB"pure_quanta"
CDS_LOCATION"R3594"
$SEC"1"
CDS_SEC"1";
"B"
$PN"2"10;
"A"
$PN"1"1;
%"Q_RES"
"1","(850,2650)","0","pure_quanta","I26";
;
PART_NUMBER"CS03322FB03"
MATERIAL"CHIP"
TOLERANCE"1%"
VALUE"33.2"
$LOCATION"R3595"
WATTAGE"1/16W"
PACK_TYPE"0402LF"
CDS_LIB"pure_quanta"
CDS_LOCATION"R3595"
$SEC"1"
CDS_SEC"1";
"B"
$PN"2"11;
"A"
$PN"1"4;
%"Q_RES"
"1","(825,3575)","0","pure_quanta","I3";
;
PART_NUMBER"CS03322FB03"
TOLERANCE"1%"
VALUE"33.2"
MATERIAL"CHIP"
$LOCATION"R3587"
CDS_LIB"pure_quanta"
WATTAGE"1/16W"
PACK_TYPE"0402LF"
CDS_LOCATION"R3587"
$SEC"1"
CDS_SEC"1";
"B"
$PN"2"5;
"A"
$PN"1"4;
%"Q_RES"
"1","(825,3625)","0","pure_quanta","I4";
;
PART_NUMBER"CS03322FB03"
WATTAGE"1/16W"
PACK_TYPE"0402LF"
MATERIAL"CHIP"
VALUE"33.2"
TOLERANCE"1%"
$LOCATION"R3586"
CDS_LIB"pure_quanta"
CDS_LOCATION"R3586"
$SEC"1"
CDS_SEC"1";
"B"
$PN"2"6;
"A"
$PN"1"1;
END.
